(kicad_pcb
	(version 20260206)
	(generator "pcbnew")
	(generator_version "10.0")
	(general
		(thickness 1.6)
		(legacy_teardrops no)
	)
	(paper "A4")
	(title_block
		(title "Bryce Canyon_R.DPB_16317-1_OCP.brd")
		(comment 1 "Bryce Canyon / footprints 29-33 of 2099")
	)
	(layers
		(0 "F.Cu" signal "TOP")
		(4 "In1.Cu" signal "L2GND")
		(6 "In2.Cu" signal "L3")
		(8 "In3.Cu" signal "L4VCC")
		(10 "In4.Cu" signal "L5VCC")
		(12 "In5.Cu" signal "L6")
		(14 "In6.Cu" signal "L7GND")
		(2 "B.Cu" signal "BOTTOM")
		(9 "F.Adhes" user "F.Adhesive")
		(11 "B.Adhes" user "B.Adhesive")
		(13 "F.Paste" user "Package Geometry/Pastemask Top")
		(15 "B.Paste" user "Package Geometry/Pastemask Bottom")
		(5 "F.SilkS" user "Ref Des/Silkscreen Top")
		(7 "B.SilkS" user "Ref Des/Silkscreen Bottom")
		(1 "F.Mask" user "Board Geometry/Soldermask Top")
		(3 "B.Mask" user "Board Geometry/Soldermask Bottom")
		(17 "Dwgs.User" user "User.Drawings")
		(19 "Cmts.User" user "User.Comments")
		(21 "Eco1.User" user "User.Eco1")
		(23 "Eco2.User" user "User.Eco2")
		(25 "Edge.Cuts" user "Board Geometry/Outline")
		(27 "Margin" user)
		(31 "F.CrtYd" user "Package Geometry/Place Bound Top")
		(29 "B.CrtYd" user "Package Geometry/Place Bound Bottom")
		(35 "F.Fab" user "Ref Des/Assembly Top")
		(33 "B.Fab" user "Ref Des/Assembly Bottom")
	)
	(footprint ""
		(layer "F.Cu")
		(at 378.968 -99.187)
		(property "Reference" "R443"
			(at 0 0 0)
			(layer "F.SilkS")
			(hide yes)
			(effects
				(font
					(size 1.27 1.27)
				)
			)
		)
		(property "Value" "91R3F-1-GP"
			(at -0.0254 -2.5146 0)
			(unlocked yes)
			(layer "F.Fab")
			(hide yes)
			(effects
				(font
					(size 1.016 1.016)
					(thickness 0.1524)
				)
			)
		)
		(property "Device Type" "R603H22"
			(at -0.0254 -4.0386 0)
			(unlocked yes)
			(layer "F.Fab")
			(hide yes)
			(effects
				(font
					(size 1.016 1.016)
					(thickness 0.1524)
				)
			)
		)
		(duplicate_pad_numbers_are_jumpers no)
		(fp_line
			(start -0.4826 0)
			(end -0.2032 0)
			(stroke
				(width 0.2032)
				(type default)
			)
			(layer "F.SilkS")
		)
		(fp_line
			(start 0.2032 0)
			(end 0.4826 0)
			(stroke
				(width 0.2032)
				(type default)
			)
			(layer "F.SilkS")
		)
		(fp_rect
			(start -0.5842 1.3335)
			(end 0.5842 -1.3335)
			(stroke
				(width 0)
				(type default)
			)
			(fill no)
			(layer "F.CrtYd")
		)
		(fp_rect
			(start -0.5842 1.3335)
			(end 0.5842 -1.3335)
			(stroke
				(width 0)
				(type default)
			)
			(fill no)
			(layer "F.Fab")
		)
		(pad "1" smd custom
			(at 0 -0.762)
			(size 0.2159 0.2159)
			(layers "F.Cu" "F.Mask" "F.Paste")
			(net "P5V_B_3")
			(options
				(clearance outline)
				(anchor circle)
			)
			(primitives
				(gr_poly
					(pts
						(arc
							(start -0.3302 -0.4318)
							(mid -0.402042 -0.402042)
							(end -0.4318 -0.3302)
						)
						(arc
							(start -0.4318 0.3302)
							(mid -0.402042 0.402042)
							(end -0.3302 0.4318)
						)
						(arc
							(start 0.3302 0.4318)
							(mid 0.402042 0.402042)
							(end 0.4318 0.3302)
						)
						(arc
							(start 0.4318 -0.3302)
							(mid 0.402042 -0.402042)
							(end 0.3302 -0.4318)
						)
					)
					(width 0)
					(fill yes)
				)
			)
		)
		(pad "2" smd custom
			(at 0 0.762)
			(size 0.2159 0.2159)
			(layers "F.Cu" "F.Mask" "F.Paste")
			(net "DRV_ACT_20")
			(options
				(clearance outline)
				(anchor circle)
			)
			(primitives
				(gr_poly
					(pts
						(arc
							(start -0.3302 -0.4318)
							(mid -0.402042 -0.402042)
							(end -0.4318 -0.3302)
						)
						(arc
							(start -0.4318 0.3302)
							(mid -0.402042 0.402042)
							(end -0.3302 0.4318)
						)
						(arc
							(start 0.3302 0.4318)
							(mid 0.402042 0.402042)
							(end 0.4318 0.3302)
						)
						(arc
							(start 0.4318 -0.3302)
							(mid 0.402042 -0.402042)
							(end 0.3302 -0.4318)
						)
					)
					(width 0)
					(fill yes)
				)
			)
		)
	)
	(footprint ""
		(layer "F.Cu")
		(at 46.482 -254.508 -90)
		(property "Reference" "R185"
			(at 0 0 270)
			(layer "F.SilkS")
			(hide yes)
			(effects
				(font
					(size 1.27 1.27)
				)
			)
		)
		(property "Value" "300KR2F-GP"
			(at 0.064008 -3.993896 270)
			(unlocked yes)
			(layer "F.Fab")
			(hide yes)
			(effects
				(font
					(size 1.016 1.016)
					(thickness 0.1524)
				)
			)
		)
		(property "Device Type" "R402H16"
			(at 0.064008 -5.517896 270)
			(unlocked yes)
			(layer "F.Fab")
			(hide yes)
			(effects
				(font
					(size 1.016 1.016)
					(thickness 0.1524)
				)
			)
		)
		(duplicate_pad_numbers_are_jumpers no)
		(fp_line
			(start -0.508 -0.9398)
			(end -0.508 0.9398)
			(stroke
				(width 0.1524)
				(type default)
			)
			(layer "F.SilkS")
		)
		(fp_line
			(start 0.508 -0.9398)
			(end -0.508 -0.9398)
			(stroke
				(width 0.1524)
				(type default)
			)
			(layer "F.SilkS")
		)
		(fp_rect
			(start -0.508 0.9398)
			(end 0.508 -0.9398)
			(stroke
				(width 0)
				(type default)
			)
			(fill no)
			(layer "F.CrtYd")
		)
		(fp_rect
			(start -0.508 0.9398)
			(end 0.508 -0.9398)
			(stroke
				(width 0)
				(type default)
			)
			(fill no)
			(layer "F.Fab")
		)
		(pad "1" smd custom
			(at 0 -0.4445 270)
			(size 0.1397 0.1397)
			(layers "F.Cu" "F.Mask" "F.Paste")
			(net "SW_HDD_N1")
			(options
				(clearance outline)
				(anchor circle)
			)
			(primitives
				(gr_poly
					(pts
						(arc
							(start -0.1778 -0.2794)
							(mid -0.249642 -0.249642)
							(end -0.2794 -0.1778)
						)
						(arc
							(start -0.2794 0.1778)
							(mid -0.249642 0.249642)
							(end -0.1778 0.2794)
						)
						(arc
							(start 0.1778 0.2794)
							(mid 0.249642 0.249642)
							(end 0.2794 0.1778)
						)
						(arc
							(start 0.2794 -0.1778)
							(mid 0.249642 -0.249642)
							(end 0.1778 -0.2794)
						)
					)
					(width 0)
					(fill yes)
				)
			)
		)
		(pad "2" smd custom
			(at 0 0.4445 270)
			(size 0.1397 0.1397)
			(layers "F.Cu" "F.Mask" "F.Paste")
			(net "P12V_B")
			(options
				(clearance outline)
				(anchor circle)
			)
			(primitives
				(gr_poly
					(pts
						(arc
							(start -0.1778 -0.2794)
							(mid -0.249642 -0.249642)
							(end -0.2794 -0.1778)
						)
						(arc
							(start -0.2794 0.1778)
							(mid -0.249642 0.249642)
							(end -0.1778 0.2794)
						)
						(arc
							(start 0.1778 0.2794)
							(mid 0.249642 0.249642)
							(end 0.2794 0.1778)
						)
						(arc
							(start 0.2794 -0.1778)
							(mid 0.249642 -0.249642)
							(end 0.1778 -0.2794)
						)
					)
					(width 0)
					(fill yes)
				)
			)
		)
	)
	(footprint ""
		(layer "F.Cu")
		(at 209.423 -208.026 -90)
		(property "Reference" "R45"
			(at 0 0 270)
			(layer "F.SilkS")
			(hide yes)
			(effects
				(font
					(size 1.27 1.27)
				)
			)
		)
		(property "Value" "4K7R2F-GP"
			(at 0.064008 -3.993896 270)
			(unlocked yes)
			(layer "F.Fab")
			(hide yes)
			(effects
				(font
					(size 1.016 1.016)
					(thickness 0.1524)
				)
			)
		)
		(property "Device Type" "R402H16"
			(at 0.064008 -5.517896 270)
			(unlocked yes)
			(layer "F.Fab")
			(hide yes)
			(effects
				(font
					(size 1.016 1.016)
					(thickness 0.1524)
				)
			)
		)
		(duplicate_pad_numbers_are_jumpers no)
		(fp_line
			(start -0.508 -0.9398)
			(end -0.508 0.9398)
			(stroke
				(width 0.1524)
				(type default)
			)
			(layer "F.SilkS")
		)
		(fp_line
			(start 0.508 -0.9398)
			(end -0.508 -0.9398)
			(stroke
				(width 0.1524)
				(type default)
			)
			(layer "F.SilkS")
		)
		(fp_rect
			(start -0.508 0.9398)
			(end 0.508 -0.9398)
			(stroke
				(width 0)
				(type default)
			)
			(fill no)
			(layer "F.CrtYd")
		)
		(fp_rect
			(start -0.508 0.9398)
			(end 0.508 -0.9398)
			(stroke
				(width 0)
				(type default)
			)
			(fill no)
			(layer "F.Fab")
		)
		(pad "1" smd custom
			(at 0 -0.4445 270)
			(size 0.1397 0.1397)
			(layers "F.Cu" "F.Mask" "F.Paste")
			(net "IO_EXP5_A0")
			(options
				(clearance outline)
				(anchor circle)
			)
			(primitives
				(gr_poly
					(pts
						(arc
							(start -0.1778 -0.2794)
							(mid -0.249642 -0.249642)
							(end -0.2794 -0.1778)
						)
						(arc
							(start -0.2794 0.1778)
							(mid -0.249642 0.249642)
							(end -0.1778 0.2794)
						)
						(arc
							(start 0.1778 0.2794)
							(mid 0.249642 0.249642)
							(end 0.2794 0.1778)
						)
						(arc
							(start 0.2794 -0.1778)
							(mid 0.249642 -0.249642)
							(end 0.1778 -0.2794)
						)
					)
					(width 0)
					(fill yes)
				)
			)
		)
		(pad "2" smd custom
			(at 0 0.4445 270)
			(size 0.1397 0.1397)
			(layers "F.Cu" "F.Mask" "F.Paste")
			(net "GND")
			(options
				(clearance outline)
				(anchor circle)
			)
			(primitives
				(gr_poly
					(pts
						(arc
							(start -0.1778 -0.2794)
							(mid -0.249642 -0.249642)
							(end -0.2794 -0.1778)
						)
						(arc
							(start -0.2794 0.1778)
							(mid -0.249642 0.249642)
							(end -0.1778 0.2794)
						)
						(arc
							(start 0.1778 0.2794)
							(mid 0.249642 0.249642)
							(end 0.2794 0.1778)
						)
						(arc
							(start 0.2794 -0.1778)
							(mid 0.249642 -0.249642)
							(end 0.1778 -0.2794)
						)
					)
					(width 0)
					(fill yes)
				)
			)
		)
	)
	(footprint ""
		(layer "F.Cu")
		(at 85.5472 -131.2672 -90)
		(property "Reference" "R403"
			(at 0 0 270)
			(layer "F.SilkS")
			(hide yes)
			(effects
				(font
					(size 1.27 1.27)
				)
			)
		)
		(property "Value" "0R2J-2-GP"
			(at 0.064008 -3.993896 270)
			(unlocked yes)
			(layer "F.Fab")
			(hide yes)
			(effects
				(font
					(size 1.016 1.016)
					(thickness 0.1524)
				)
			)
		)
		(property "Device Type" "R402H16"
			(at 0.064008 -5.517896 270)
			(unlocked yes)
			(layer "F.Fab")
			(hide yes)
			(effects
				(font
					(size 1.016 1.016)
					(thickness 0.1524)
				)
			)
		)
		(duplicate_pad_numbers_are_jumpers no)
		(fp_line
			(start -0.508 -0.9398)
			(end -0.508 0.9398)
			(stroke
				(width 0.1524)
				(type default)
			)
			(layer "F.SilkS")
		)
		(fp_line
			(start 0.508 -0.9398)
			(end -0.508 -0.9398)
			(stroke
				(width 0.1524)
				(type default)
			)
			(layer "F.SilkS")
		)
		(fp_rect
			(start -0.508 0.9398)
			(end 0.508 -0.9398)
			(stroke
				(width 0)
				(type default)
			)
			(fill no)
			(layer "F.CrtYd")
		)
		(fp_rect
			(start -0.508 0.9398)
			(end 0.508 -0.9398)
			(stroke
				(width 0)
				(type default)
			)
			(fill no)
			(layer "F.Fab")
		)
		(pad "1" smd custom
			(at 0 -0.4445 270)
			(size 0.1397 0.1397)
			(layers "F.Cu" "F.Mask" "F.Paste")
			(net "DRIVE_B_14_PWR")
			(options
				(clearance outline)
				(anchor circle)
			)
			(primitives
				(gr_poly
					(pts
						(arc
							(start -0.1778 -0.2794)
							(mid -0.249642 -0.249642)
							(end -0.2794 -0.1778)
						)
						(arc
							(start -0.2794 0.1778)
							(mid -0.249642 0.249642)
							(end -0.1778 0.2794)
						)
						(arc
							(start 0.1778 0.2794)
							(mid 0.249642 0.249642)
							(end 0.2794 0.1778)
						)
						(arc
							(start 0.2794 -0.1778)
							(mid 0.249642 -0.249642)
							(end 0.1778 -0.2794)
						)
					)
					(width 0)
					(fill yes)
				)
			)
		)
		(pad "2" smd custom
			(at 0 0.4445 270)
			(size 0.1397 0.1397)
			(layers "F.Cu" "F.Mask" "F.Paste")
			(net "SW_PWR_R_HDD14")
			(options
				(clearance outline)
				(anchor circle)
			)
			(primitives
				(gr_poly
					(pts
						(arc
							(start -0.1778 -0.2794)
							(mid -0.249642 -0.249642)
							(end -0.2794 -0.1778)
						)
						(arc
							(start -0.2794 0.1778)
							(mid -0.249642 0.249642)
							(end -0.1778 0.2794)
						)
						(arc
							(start 0.1778 0.2794)
							(mid 0.249642 0.249642)
							(end 0.2794 0.1778)
						)
						(arc
							(start 0.2794 -0.1778)
							(mid 0.249642 -0.249642)
							(end 0.1778 -0.2794)
						)
					)
					(width 0)
					(fill yes)
				)
			)
		)
	)
	(footprint ""
		(layer "F.Cu")
		(at 410.464 -214.249)
		(property "Reference" "R349"
			(at 0 0 0)
			(layer "F.SilkS")
			(hide yes)
			(effects
				(font
					(size 1.27 1.27)
				)
			)
		)
		(property "Value" "91R3F-1-GP"
			(at -0.0254 -2.5146 0)
			(unlocked yes)
			(layer "F.Fab")
			(hide yes)
			(effects
				(font
					(size 1.016 1.016)
					(thickness 0.1524)
				)
			)
		)
		(property "Device Type" "R603H22"
			(at -0.0254 -4.0386 0)
			(unlocked yes)
			(layer "F.Fab")
			(hide yes)
			(effects
				(font
					(size 1.016 1.016)
					(thickness 0.1524)
				)
			)
		)
		(duplicate_pad_numbers_are_jumpers no)
		(fp_line
			(start -0.4826 0)
			(end -0.2032 0)
			(stroke
				(width 0.2032)
				(type default)
			)
			(layer "F.SilkS")
		)
		(fp_line
			(start 0.2032 0)
			(end 0.4826 0)
			(stroke
				(width 0.2032)
				(type default)
			)
			(layer "F.SilkS")
		)
		(fp_rect
			(start -0.5842 1.3335)
			(end 0.5842 -1.3335)
			(stroke
				(width 0)
				(type default)
			)
			(fill no)
			(layer "F.CrtYd")
		)
		(fp_rect
			(start -0.5842 1.3335)
			(end 0.5842 -1.3335)
			(stroke
				(width 0)
				(type default)
			)
			(fill no)
			(layer "F.Fab")
		)
		(pad "1" smd custom
			(at 0 -0.762)
			(size 0.2159 0.2159)
			(layers "F.Cu" "F.Mask" "F.Paste")
			(net "P5V_B_3")
			(options
				(clearance outline)
				(anchor circle)
			)
			(primitives
				(gr_poly
					(pts
						(arc
							(start -0.3302 -0.4318)
							(mid -0.402042 -0.402042)
							(end -0.4318 -0.3302)
						)
						(arc
							(start -0.4318 0.3302)
							(mid -0.402042 0.402042)
							(end -0.3302 0.4318)
						)
						(arc
							(start 0.3302 0.4318)
							(mid 0.402042 0.402042)
							(end 0.4318 0.3302)
						)
						(arc
							(start 0.4318 -0.3302)
							(mid 0.402042 -0.402042)
							(end 0.3302 -0.4318)
						)
					)
					(width 0)
					(fill yes)
				)
			)
		)
		(pad "2" smd custom
			(at 0 0.762)
			(size 0.2159 0.2159)
			(layers "F.Cu" "F.Mask" "F.Paste")
			(net "DRV_ACT_9")
			(options
				(clearance outline)
				(anchor circle)
			)
			(primitives
				(gr_poly
					(pts
						(arc
							(start -0.3302 -0.4318)
							(mid -0.402042 -0.402042)
							(end -0.4318 -0.3302)
						)
						(arc
							(start -0.4318 0.3302)
							(mid -0.402042 0.402042)
							(end -0.3302 0.4318)
						)
						(arc
							(start 0.3302 0.4318)
							(mid 0.402042 0.402042)
							(end 0.4318 0.3302)
						)
						(arc
							(start 0.4318 -0.3302)
							(mid 0.402042 -0.402042)
							(end 0.3302 -0.4318)
						)
					)
					(width 0)
					(fill yes)
				)
			)
		)
	)
)
